# BASEBOARD_FAB2 (Tioga Pass) — schematic netlist excerpt (pin names and nets, part order shuffled) for the footprints in the layout excerpt that follows; sources: Cadence DE-HDL packaged netlist, KiCad conversion of Wiwynn_Tioga_Pass_MB.brd

R2T73  RES  150.0 1% CHIP  pkg 0402  page 93 : A = PVCCIO_CPU1 ; B = H_CPU1_PROCHOT_G_N
R3P45  374R2F-1-GP  1%  pkg SMD-RG  page 92 : \1\ = P3V3 ; \2\ = P0V7_GTL2104_VREF_1
C3M41  CAP  0.22UF 16V 10% X7R  pkg 0402  page 129 : A = DMI_CPU0_PCH_RX_DN<1> ; B = DMI_CPU0_PCH_RX_C_DN<1>

(kicad_pcb
	(version 20260206)
	(generator "pcbnew")
	(generator_version "10.0")
	(general
		(thickness 1.6)
		(legacy_teardrops no)
	)
	(paper "A4")
	(title_block
		(title "Wiwynn_Tioga_Pass_MB.brd")
		(comment 1 "Tioga Pass / footprints 3284-3286 of 4770")
	)
	(layers
		(0 "F.Cu" signal "TOP")
		(4 "In1.Cu" signal "L2GND")
		(6 "In2.Cu" signal "L3")
		(8 "In3.Cu" signal "L4GND")
		(10 "In4.Cu" signal "L5")
		(12 "In5.Cu" signal "L6GND")
		(14 "In6.Cu" signal "L7VCC")
		(16 "In7.Cu" signal "L8VCC")
		(18 "In8.Cu" signal "L9GND")
		(20 "In9.Cu" signal "L10")
		(22 "In10.Cu" signal "L11GND")
		(24 "In11.Cu" signal "L12")
		(26 "In12.Cu" signal "L13GND")
		(2 "B.Cu" signal "BOTTOM")
		(9 "F.Adhes" user "F.Adhesive")
		(11 "B.Adhes" user "B.Adhesive")
		(13 "F.Paste" user "Package Geometry/Pastemask Top")
		(15 "B.Paste" user "Package Geometry/Pastemask Bottom")
		(5 "F.SilkS" user "Ref Des/Silkscreen Top")
		(7 "B.SilkS" user "Ref Des/Silkscreen Bottom")
		(1 "F.Mask" user "Board Geometry/Soldermask Top")
		(3 "B.Mask" user "Board Geometry/Soldermask Bottom")
		(17 "Dwgs.User" user "User.Drawings")
		(19 "Cmts.User" user "User.Comments")
		(21 "Eco1.User" user "User.Eco1")
		(23 "Eco2.User" user "User.Eco2")
		(25 "Edge.Cuts" user "Board Geometry/Outline")
		(27 "Margin" user)
		(31 "F.CrtYd" user "Package Geometry/Place Bound Top")
		(29 "B.CrtYd" user "Package Geometry/Place Bound Bottom")
		(35 "F.Fab" user "Ref Des/Assembly Top")
		(33 "B.Fab" user "Ref Des/Assembly Bottom")
	)
	(footprint ""
		(layer "B.Cu")
		(at 374.4214 -59.9694)
		(property "Reference" "R3P45"
			(at 0 0 0)
			(layer "B.SilkS")
			(hide yes)
			(effects
				(font
					(size 1.27 1.27)
				)
				(justify mirror)
			)
		)
		(property "Value" "*"
			(at -0.064008 -4.108196 0)
			(unlocked yes)
			(layer "B.Fab")
			(hide yes)
			(effects
				(font
					(size 1.27 1.016)
					(thickness 0.1524)
				)
				(justify mirror)
			)
		)
		(property "Device Type" "374R2F-1-GP_SMD-RG-374R2F-1-GPA"
			(at -0.064008 -5.632196 0)
			(unlocked yes)
			(layer "B.Fab")
			(hide yes)
			(effects
				(font
					(size 1.27 1.016)
					(thickness 0.1524)
				)
				(justify mirror)
			)
		)
		(duplicate_pad_numbers_are_jumpers no)
		(fp_line
			(start -0.508 -0.9398)
			(end 0.508 -0.9398)
			(stroke
				(width 0.1524)
				(type default)
			)
			(layer "B.SilkS")
		)
		(fp_line
			(start 0.508 -0.9398)
			(end 0.508 0.9398)
			(stroke
				(width 0.1524)
				(type default)
			)
			(layer "B.SilkS")
		)
		(fp_rect
			(start 0.508 0.9398)
			(end -0.508 -0.9398)
			(stroke
				(width 0)
				(type default)
			)
			(fill no)
			(layer "B.CrtYd")
		)
		(fp_rect
			(start 0.508 0.9398)
			(end -0.508 -0.9398)
			(stroke
				(width 0)
				(type default)
			)
			(fill no)
			(layer "B.Fab")
		)
		(pad "1" smd custom
			(at 0 -0.4445 180)
			(size 0.1397 0.1397)
			(layers "B.Cu" "B.Mask" "B.Paste")
			(net "P3V3")
			(options
				(clearance outline)
				(anchor circle)
			)
			(primitives
				(gr_poly
					(pts
						(arc
							(start -0.1778 0.2794)
							(mid -0.249642 0.249642)
							(end -0.2794 0.1778)
						)
						(arc
							(start -0.2794 -0.1778)
							(mid -0.249642 -0.249642)
							(end -0.1778 -0.2794)
						)
						(arc
							(start 0.1778 -0.2794)
							(mid 0.249642 -0.249642)
							(end 0.2794 -0.1778)
						)
						(arc
							(start 0.2794 0.1778)
							(mid 0.249642 0.249642)
							(end 0.1778 0.2794)
						)
					)
					(width 0)
					(fill yes)
				)
			)
		)
		(pad "2" smd custom
			(at 0 0.4445 180)
			(size 0.1397 0.1397)
			(layers "B.Cu" "B.Mask" "B.Paste")
			(net "P0V7_GTL2104_VREF_1")
			(options
				(clearance outline)
				(anchor circle)
			)
			(primitives
				(gr_poly
					(pts
						(arc
							(start -0.1778 0.2794)
							(mid -0.249642 0.249642)
							(end -0.2794 0.1778)
						)
						(arc
							(start -0.2794 -0.1778)
							(mid -0.249642 -0.249642)
							(end -0.1778 -0.2794)
						)
						(arc
							(start 0.1778 -0.2794)
							(mid 0.249642 -0.249642)
							(end 0.2794 -0.1778)
						)
						(arc
							(start 0.2794 0.1778)
							(mid 0.249642 0.249642)
							(end 0.1778 0.2794)
						)
					)
					(width 0)
					(fill yes)
				)
			)
		)
	)
	(footprint ""
		(layer "B.Cu")
		(at 373.8372 -46.8376 -90)
		(property "Reference" "R2T73"
			(at 0 0 90)
			(layer "B.SilkS")
			(hide yes)
			(effects
				(font
					(size 1.27 1.27)
				)
				(justify mirror)
			)
		)
		(property "Value" ""
			(at 0 0 90)
			(layer "B.Fab")
			(effects
				(font
					(size 1.27 1.27)
				)
				(justify mirror)
			)
		)
		(duplicate_pad_numbers_are_jumpers no)
		(fp_poly
			(pts
				(xy 0.2794 -0.1016) (xy -0.2794 -0.1016) (xy -0.2794 0.9906) (xy 0.2794 0.9906)
			)
			(stroke
				(width 0)
				(type default)
			)
			(fill no)
			(layer "B.CrtYd")
		)
		(fp_line
			(start -0.2794 0.9906)
			(end -0.2794 -0.1016)
			(stroke
				(width 0.1)
				(type default)
			)
			(layer "B.Fab")
		)
		(fp_line
			(start 0.2794 0.9906)
			(end -0.2794 0.9906)
			(stroke
				(width 0.1)
				(type default)
			)
			(layer "B.Fab")
		)
		(fp_line
			(start -0.2794 -0.1016)
			(end 0.2794 -0.1016)
			(stroke
				(width 0.1)
				(type default)
			)
			(layer "B.Fab")
		)
		(fp_line
			(start 0.2794 -0.1016)
			(end 0.2794 0.9906)
			(stroke
				(width 0.1)
				(type default)
			)
			(layer "B.Fab")
		)
		(pad "1" smd rect
			(at 0 0 90)
			(size 0.508 0.508)
			(layers "B.Cu" "B.Mask" "B.Paste")
			(net "PVCCIO_CPU1")
		)
		(pad "2" smd rect
			(at 0 0.889 90)
			(size 0.508 0.508)
			(layers "B.Cu" "B.Mask" "B.Paste")
			(net "H_CPU1_PROCHOT_G_N")
		)
		(zone
			(layer "B.Cu")
			(hatch none 0.5)
			(connect_pads
				(clearance 0)
			)
			(min_thickness 0.25)
			(keepout
				(tracks not_allowed)
				(vias allowed)
				(pads allowed)
				(copperpour not_allowed)
				(footprints allowed)
			)
			(placement
				(enabled no)
				(sheetname "")
			)
			(fill
				(thermal_gap 0.5)
				(thermal_bridge_width 0.5)
				(island_removal_mode 0)
			)
			(polygon
				(pts
					(xy 373.2022 -46.5836) (xy 373.2022 -47.0916) (xy 373.5832 -47.0916) (xy 373.5832 -46.5836)
				)
			)
		)
		(zone
			(layer "B.Cu")
			(hatch none 0.5)
			(connect_pads
				(clearance 0)
			)
			(min_thickness 0.25)
			(keepout
				(tracks allowed)
				(vias not_allowed)
				(pads allowed)
				(copperpour not_allowed)
				(footprints allowed)
			)
			(placement
				(enabled no)
				(sheetname "")
			)
			(fill
				(thermal_gap 0.5)
				(thermal_bridge_width 0.5)
				(island_removal_mode 0)
			)
			(polygon
				(pts
					(xy 373.5832 -46.5836) (xy 373.5832 -47.0916) (xy 373.2022 -47.0916) (xy 373.2022 -46.5836)
				)
			)
		)
	)
	(footprint ""
		(layer "B.Cu")
		(at 365.506 -113.792 -90)
		(property "Reference" "C3M41"
			(at 0 0 90)
			(layer "B.SilkS")
			(hide yes)
			(effects
				(font
					(size 1.27 1.27)
				)
				(justify mirror)
			)
		)
		(property "Value" ""
			(at 0 0 90)
			(layer "B.Fab")
			(effects
				(font
					(size 1.27 1.27)
				)
				(justify mirror)
			)
		)
		(duplicate_pad_numbers_are_jumpers no)
		(fp_poly
			(pts
				(xy -0.3048 -0.1016) (xy -0.3048 0.9906) (xy 0.3048 0.9906) (xy 0.3048 -0.1016)
			)
			(stroke
				(width 0)
				(type default)
			)
			(fill no)
			(layer "B.CrtYd")
		)
		(fp_line
			(start -0.3048 0.9906)
			(end -0.3048 -0.1016)
			(stroke
				(width 0.1)
				(type default)
			)
			(layer "B.Fab")
		)
		(fp_line
			(start 0.3048 0.9906)
			(end -0.3048 0.9906)
			(stroke
				(width 0.1)
				(type default)
			)
			(layer "B.Fab")
		)
		(fp_line
			(start -0.3048 -0.1016)
			(end 0.3048 -0.1016)
			(stroke
				(width 0.1)
				(type default)
			)
			(layer "B.Fab")
		)
		(fp_line
			(start 0.3048 -0.1016)
			(end 0.3048 0.9906)
			(stroke
				(width 0.1)
				(type default)
			)
			(layer "B.Fab")
		)
		(pad "1" smd rect
			(at 0 0 90)
			(size 0.508 0.508)
			(layers "B.Cu" "B.Mask" "B.Paste")
			(net "DMI_CPU0_PCH_RX_DN<1>")
		)
		(pad "2" smd rect
			(at 0 0.889 90)
			(size 0.508 0.508)
			(layers "B.Cu" "B.Mask" "B.Paste")
			(net "DMI_CPU0_PCH_RX_C_DN<1>")
		)
		(zone
			(layer "B.Cu")
			(hatch none 0.5)
			(connect_pads
				(clearance 0)
			)
			(min_thickness 0.25)
			(keepout
				(tracks not_allowed)
				(vias allowed)
				(pads allowed)
				(copperpour not_allowed)
				(footprints allowed)
			)
			(placement
				(enabled no)
				(sheetname "")
			)
			(fill
				(thermal_gap 0.5)
				(thermal_bridge_width 0.5)
				(island_removal_mode 0)
			)
			(polygon
				(pts
					(xy 364.871 -113.538) (xy 364.871 -114.046) (xy 365.252 -114.046) (xy 365.252 -113.538)
				)
			)
		)
		(zone
			(layer "B.Cu")
			(hatch none 0.5)
			(connect_pads
				(clearance 0)
			)
			(min_thickness 0.25)
			(keepout
				(tracks allowed)
				(vias not_allowed)
				(pads allowed)
				(copperpour not_allowed)
				(footprints allowed)
			)
			(placement
				(enabled no)
				(sheetname "")
			)
			(fill
				(thermal_gap 0.5)
				(thermal_bridge_width 0.5)
				(island_removal_mode 0)
			)
			(polygon
				(pts
					(xy 365.252 -113.538) (xy 365.252 -114.046) (xy 364.871 -114.046) (xy 364.871 -113.538)
				)
			)
		)
	)
)
